# BASEBOARD_FAB2 (Tioga Pass) — schematic netlist excerpt (pin names and nets, part order shuffled) for the footprints in the layout excerpt that follows; sources: Cadence DE-HDL packaged netlist, KiCad conversion of Wiwynn_Tioga_Pass_MB.brd

Q9W1  FET_N  2N7002 FET  pkg SOT23LF  page 249
  GATE  = BMC_TPM_HW_C_RST
  SRC  = GND
  DRN  = FM_TPM_PRES_RST_N

R2T4  RES  1.0K 0.1% CHIP  pkg 0402  page 240 : A = P3V3_STBY ; B = GND
R25W115  RES  4.75K 1% EMPTY  pkg 0402  page 150 : A = P3V3_STBY ; B = TP_RGMII1TXD3_GPIOT5

(kicad_pcb
	(version 20260206)
	(generator "pcbnew")
	(generator_version "10.0")
	(general
		(thickness 1.6)
		(legacy_teardrops no)
	)
	(paper "A4")
	(title_block
		(title "Wiwynn_Tioga_Pass_MB.brd")
		(comment 1 "Tioga Pass / footprints 2911-2913 of 4770")
	)
	(layers
		(0 "F.Cu" signal "TOP")
		(4 "In1.Cu" signal "L2GND")
		(6 "In2.Cu" signal "L3")
		(8 "In3.Cu" signal "L4GND")
		(10 "In4.Cu" signal "L5")
		(12 "In5.Cu" signal "L6GND")
		(14 "In6.Cu" signal "L7VCC")
		(16 "In7.Cu" signal "L8VCC")
		(18 "In8.Cu" signal "L9GND")
		(20 "In9.Cu" signal "L10")
		(22 "In10.Cu" signal "L11GND")
		(24 "In11.Cu" signal "L12")
		(26 "In12.Cu" signal "L13GND")
		(2 "B.Cu" signal "BOTTOM")
		(9 "F.Adhes" user "F.Adhesive")
		(11 "B.Adhes" user "B.Adhesive")
		(13 "F.Paste" user "Package Geometry/Pastemask Top")
		(15 "B.Paste" user "Package Geometry/Pastemask Bottom")
		(5 "F.SilkS" user "Ref Des/Silkscreen Top")
		(7 "B.SilkS" user "Ref Des/Silkscreen Bottom")
		(1 "F.Mask" user "Board Geometry/Soldermask Top")
		(3 "B.Mask" user "Board Geometry/Soldermask Bottom")
		(17 "Dwgs.User" user "User.Drawings")
		(19 "Cmts.User" user "User.Comments")
		(21 "Eco1.User" user "User.Eco1")
		(23 "Eco2.User" user "User.Eco2")
		(25 "Edge.Cuts" user "Board Geometry/Outline")
		(27 "Margin" user)
		(31 "F.CrtYd" user "Package Geometry/Place Bound Top")
		(29 "B.CrtYd" user "Package Geometry/Place Bound Bottom")
		(35 "F.Fab" user "Ref Des/Assembly Top")
		(33 "B.Fab" user "Ref Des/Assembly Bottom")
	)
	(footprint ""
		(layer "B.Cu")
		(at 452.5645 -19.177 -90)
		(property "Reference" "Q9W1"
			(at 0.229362 -1.2065 270)
			(unlocked yes)
			(layer "B.SilkS")
			(effects
				(font
					(size 0.4064 0.254)
					(thickness 0.1524)
				)
				(justify left mirror)
			)
		)
		(property "Value" ""
			(at 0 0 90)
			(layer "B.Fab")
			(effects
				(font
					(size 1.27 1.27)
				)
				(justify mirror)
			)
		)
		(duplicate_pad_numbers_are_jumpers no)
		(fp_line
			(start -1.778 2.4765)
			(end -1.778 1.5875)
			(stroke
				(width 0.1524)
				(type default)
			)
			(layer "B.SilkS")
		)
		(fp_line
			(start -0.9525 2.4765)
			(end -1.778 2.4765)
			(stroke
				(width 0.1524)
				(type default)
			)
			(layer "B.SilkS")
		)
		(fp_line
			(start -0.381 0.635)
			(end -0.381 1.27)
			(stroke
				(width 0.1524)
				(type default)
			)
			(layer "B.SilkS")
		)
		(fp_line
			(start -1.778 -0.5715)
			(end -1.778 0.3175)
			(stroke
				(width 0.1524)
				(type default)
			)
			(layer "B.SilkS")
		)
		(fp_line
			(start -0.9525 -0.5715)
			(end -1.778 -0.5715)
			(stroke
				(width 0.1524)
				(type default)
			)
			(layer "B.SilkS")
		)
		(fp_circle
			(center 0.9525 -0.9271)
			(end 0.9525 -1.0541)
			(stroke
				(width 0.254)
				(type default)
			)
			(fill no)
			(layer "B.SilkS")
		)
		(fp_poly
			(pts
				(xy -1.778 2.4765) (xy -0.381 2.4765) (xy -0.381 -0.5715) (xy -1.778 -0.5715)
			)
			(stroke
				(width 0)
				(type default)
			)
			(fill no)
			(layer "B.CrtYd")
		)
		(fp_line
			(start -1.778 2.4765)
			(end -1.778 -0.5715)
			(stroke
				(width 0.1)
				(type default)
			)
			(layer "B.Fab")
		)
		(fp_line
			(start -0.381 2.4765)
			(end -1.778 2.4765)
			(stroke
				(width 0.1)
				(type default)
			)
			(layer "B.Fab")
		)
		(fp_line
			(start -1.778 -0.5715)
			(end -0.381 -0.5715)
			(stroke
				(width 0.1)
				(type default)
			)
			(layer "B.Fab")
		)
		(fp_line
			(start -0.381 -0.5715)
			(end -0.381 2.4765)
			(stroke
				(width 0.1)
				(type default)
			)
			(layer "B.Fab")
		)
		(fp_circle
			(center 0.9525 -0.9271)
			(end 0.9525 -1.0541)
			(stroke
				(width 0.254)
				(type default)
			)
			(fill no)
			(layer "B.Fab")
		)
		(pad "1" smd rect
			(at 0 0 90)
			(size 1.143 0.508)
			(layers "B.Cu" "B.Mask" "B.Paste")
			(net "BMC_TPM_HW_C_RST")
		)
		(pad "2" smd rect
			(at 0 1.905 90)
			(size 1.143 0.508)
			(layers "B.Cu" "B.Mask" "B.Paste")
			(net "GND")
		)
		(pad "3" smd rect
			(at -2.159 0.9525 90)
			(size 1.143 0.508)
			(layers "B.Cu" "B.Mask" "B.Paste")
			(net "FM_TPM_PRES_RST_N")
		)
	)
	(footprint ""
		(layer "B.Cu")
		(at 404.3172 -30.861 90)
		(property "Reference" "R25W115"
			(at 0.8382 -0.67818 90)
			(unlocked yes)
			(layer "B.SilkS")
			(effects
				(font
					(size 0.4064 0.254)
					(thickness 0.1524)
				)
				(justify left mirror)
			)
		)
		(property "Value" ""
			(at 0 0 90)
			(layer "B.Fab")
			(effects
				(font
					(size 1.27 1.27)
				)
				(justify mirror)
			)
		)
		(duplicate_pad_numbers_are_jumpers no)
		(fp_poly
			(pts
				(xy 0.2794 -0.1016) (xy -0.2794 -0.1016) (xy -0.2794 0.9906) (xy 0.2794 0.9906)
			)
			(stroke
				(width 0)
				(type default)
			)
			(fill no)
			(layer "B.CrtYd")
		)
		(fp_line
			(start 0.2794 -0.1016)
			(end 0.2794 0.9906)
			(stroke
				(width 0.1)
				(type default)
			)
			(layer "B.Fab")
		)
		(fp_line
			(start -0.2794 -0.1016)
			(end 0.2794 -0.1016)
			(stroke
				(width 0.1)
				(type default)
			)
			(layer "B.Fab")
		)
		(fp_line
			(start 0.2794 0.9906)
			(end -0.2794 0.9906)
			(stroke
				(width 0.1)
				(type default)
			)
			(layer "B.Fab")
		)
		(fp_line
			(start -0.2794 0.9906)
			(end -0.2794 -0.1016)
			(stroke
				(width 0.1)
				(type default)
			)
			(layer "B.Fab")
		)
		(pad "1" smd rect
			(at 0 0 270)
			(size 0.508 0.508)
			(layers "B.Cu" "B.Mask" "B.Paste")
			(net "P3V3_STBY")
		)
		(pad "2" smd rect
			(at 0 0.889 270)
			(size 0.508 0.508)
			(layers "B.Cu" "B.Mask" "B.Paste")
			(net "TP_RGMII1TXD3_GPIOT5")
		)
		(zone
			(layer "B.Cu")
			(hatch none 0.5)
			(connect_pads
				(clearance 0)
			)
			(min_thickness 0.25)
			(keepout
				(tracks allowed)
				(vias not_allowed)
				(pads allowed)
				(copperpour not_allowed)
				(footprints allowed)
			)
			(placement
				(enabled no)
				(sheetname "")
			)
			(fill
				(thermal_gap 0.5)
				(thermal_bridge_width 0.5)
				(island_removal_mode 0)
			)
			(polygon
				(pts
					(xy 404.5712 -31.115) (xy 404.5712 -30.607) (xy 404.9522 -30.607) (xy 404.9522 -31.115)
				)
			)
		)
		(zone
			(layer "B.Cu")
			(hatch none 0.5)
			(connect_pads
				(clearance 0)
			)
			(min_thickness 0.25)
			(keepout
				(tracks not_allowed)
				(vias allowed)
				(pads allowed)
				(copperpour not_allowed)
				(footprints allowed)
			)
			(placement
				(enabled no)
				(sheetname "")
			)
			(fill
				(thermal_gap 0.5)
				(thermal_bridge_width 0.5)
				(island_removal_mode 0)
			)
			(polygon
				(pts
					(xy 404.9522 -31.115) (xy 404.9522 -30.607) (xy 404.5712 -30.607) (xy 404.5712 -31.115)
				)
			)
		)
	)
	(footprint ""
		(layer "B.Cu")
		(at 463.15122 -13.215366 -90)
		(property "Reference" "R2T4"
			(at 0 0 90)
			(layer "B.SilkS")
			(hide yes)
			(effects
				(font
					(size 1.27 1.27)
				)
				(justify mirror)
			)
		)
		(property "Value" ""
			(at 0 0 90)
			(layer "B.Fab")
			(effects
				(font
					(size 1.27 1.27)
				)
				(justify mirror)
			)
		)
		(duplicate_pad_numbers_are_jumpers no)
		(fp_rect
			(start 0.2794 -0.1016)
			(end -0.2794 0.9906)
			(stroke
				(width 0)
				(type default)
			)
			(fill no)
			(layer "B.CrtYd")
		)
		(fp_line
			(start -0.2794 0.9906)
			(end -0.2794 -0.1016)
			(stroke
				(width 0.1)
				(type default)
			)
			(layer "B.Fab")
		)
		(fp_line
			(start 0.2794 0.9906)
			(end -0.2794 0.9906)
			(stroke
				(width 0.1)
				(type default)
			)
			(layer "B.Fab")
		)
		(fp_line
			(start -0.2794 -0.1016)
			(end 0.2794 -0.1016)
			(stroke
				(width 0.1)
				(type default)
			)
			(layer "B.Fab")
		)
		(fp_line
			(start 0.2794 -0.1016)
			(end 0.2794 0.9906)
			(stroke
				(width 0.1)
				(type default)
			)
			(layer "B.Fab")
		)
		(pad "1" smd rect
			(at 0 0 90)
			(size 0.508 0.508)
			(layers "B.Cu" "B.Mask" "B.Paste")
			(net "P3V3_STBY")
		)
		(pad "2" smd rect
			(at 0 0.889 90)
			(size 0.508 0.508)
			(layers "B.Cu" "B.Mask" "B.Paste")
			(net "GND")
		)
		(zone
			(layer "B.Cu")
			(hatch none 0.5)
			(connect_pads
				(clearance 0)
			)
			(min_thickness 0.25)
			(keepout
				(tracks allowed)
				(vias not_allowed)
				(pads allowed)
				(copperpour not_allowed)
				(footprints allowed)
			)
			(placement
				(enabled no)
				(sheetname "")
			)
			(fill
				(thermal_gap 0.5)
				(thermal_bridge_width 0.5)
				(island_removal_mode 0)
			)
			(polygon
				(pts
					(xy 462.89722 -12.961366) (xy 462.89722 -13.469366) (xy 462.51622 -13.469366) (xy 462.51622 -12.961366)
				)
			)
		)
		(zone
			(layer "B.Cu")
			(hatch none 0.5)
			(connect_pads
				(clearance 0)
			)
			(min_thickness 0.25)
			(keepout
				(tracks not_allowed)
				(vias allowed)
				(pads allowed)
				(copperpour not_allowed)
				(footprints allowed)
			)
			(placement
				(enabled no)
				(sheetname "")
			)
			(fill
				(thermal_gap 0.5)
				(thermal_bridge_width 0.5)
				(island_removal_mode 0)
			)
			(polygon
				(pts
					(xy 462.89722 -12.961366) (xy 462.89722 -13.469366) (xy 462.51622 -13.469366) (xy 462.51622 -12.961366)
				)
			)
		)
	)
)
